(kicad_pcb
	(version 20260206)
	(generator "pcbnew")
	(generator_version "10.0")
	(general
		(thickness 1.6)
		(legacy_teardrops no)
	)
	(paper "A4")
	(title_block
		(title "v1-chassis-manager — T6M_CM_d_v01_1031_1645.brd")
		(comment 1 "Open CloudServer (Microsoft) / footprints 364-371 of 2512")
	)
	(layers
		(0 "F.Cu" signal "TOP")
		(4 "In1.Cu" signal "GND1")
		(6 "In2.Cu" signal "IN1")
		(8 "In3.Cu" signal "VCC1")
		(10 "In4.Cu" signal "VCC2")
		(12 "In5.Cu" signal "GND2")
		(14 "In6.Cu" signal "IN2")
		(16 "In7.Cu" signal "IN3")
		(18 "In8.Cu" signal "GND3")
		(2 "B.Cu" signal "BOTTOM")
		(9 "F.Adhes" user "F.Adhesive")
		(11 "B.Adhes" user "B.Adhesive")
		(13 "F.Paste" user "Package Geometry/Pastemask Top")
		(15 "B.Paste" user "Package Geometry/Pastemask Bottom")
		(5 "F.SilkS" user "Ref Des/Silkscreen Top")
		(7 "B.SilkS" user "Ref Des/Silkscreen Bottom")
		(1 "F.Mask" user "Board Geometry/Soldermask Top")
		(3 "B.Mask" user "Board Geometry/Soldermask Bottom")
		(17 "Dwgs.User" user "User.Drawings")
		(19 "Cmts.User" user "User.Comments")
		(21 "Eco1.User" user "User.Eco1")
		(23 "Eco2.User" user "User.Eco2")
		(25 "Edge.Cuts" user "Board Geometry/Outline")
		(27 "Margin" user)
		(31 "F.CrtYd" user "Package Geometry/Place Bound Top")
		(29 "B.CrtYd" user "Package Geometry/Place Bound Bottom")
		(35 "F.Fab" user "Ref Des/Assembly Top")
		(33 "B.Fab" user "Ref Des/Assembly Bottom")
	)
	(footprint ""
		(layer "F.Cu")
		(at 62.267338 -6.726682)
		(property "Reference" "PC79"
			(at -1.87706 5.312156 0)
			(unlocked yes)
			(layer "F.SilkS")
			(effects
				(font
					(size 0.7874 0.5842)
					(thickness 0.1524)
				)
				(justify left)
			)
		)
		(property "Value" ""
			(at 0 0 0)
			(layer "F.Fab")
			(effects
				(font
					(size 1.27 1.27)
				)
			)
		)
		(duplicate_pad_numbers_are_jumpers no)
		(fp_line
			(start -2.249932 -4.533392)
			(end 2.249932 -4.533392)
			(stroke
				(width 0.1524)
				(type default)
			)
			(layer "F.SilkS")
		)
		(fp_line
			(start -2.249932 4.533392)
			(end -2.249932 -4.533392)
			(stroke
				(width 0.1524)
				(type default)
			)
			(layer "F.SilkS")
		)
		(fp_line
			(start 2.249932 -4.533392)
			(end 2.249932 4.533392)
			(stroke
				(width 0.1524)
				(type default)
			)
			(layer "F.SilkS")
		)
		(fp_line
			(start 2.249932 4.533392)
			(end -2.249932 4.533392)
			(stroke
				(width 0.1524)
				(type default)
			)
			(layer "F.SilkS")
		)
		(fp_poly
			(pts
				(xy 2.326132 -4.533392) (xy 2.326132 -5.39242) (xy -2.326132 -5.39242) (xy -2.326132 -4.533392)
			)
			(stroke
				(width 0)
				(type default)
			)
			(fill yes)
			(layer "F.SilkS")
		)
		(fp_poly
			(pts
				(xy -1.4605 4.457192) (xy -1.4605 3.750056) (xy -2.249932 3.750056) (xy -2.249932 -3.750056) (xy -1.4605 -3.750056)
				(xy -1.4605 -4.457192) (xy 1.4605 -4.457192) (xy 1.4605 -3.750056) (xy 2.249932 -3.750056) (xy 2.249932 3.750056)
				(xy 1.4605 3.750056) (xy 1.4605 4.457192)
			)
			(stroke
				(width 0)
				(type default)
			)
			(fill no)
			(layer "F.CrtYd")
		)
		(fp_line
			(start -2.249932 -3.750056)
			(end 2.249932 -3.750056)
			(stroke
				(width 0.1)
				(type default)
			)
			(layer "F.Fab")
		)
		(fp_line
			(start -2.249932 3.750056)
			(end -2.249932 -3.750056)
			(stroke
				(width 0.1)
				(type default)
			)
			(layer "F.Fab")
		)
		(fp_line
			(start 2.249932 -3.750056)
			(end 2.249932 3.750056)
			(stroke
				(width 0.1)
				(type default)
			)
			(layer "F.Fab")
		)
		(fp_line
			(start 2.249932 3.750056)
			(end -2.249932 3.750056)
			(stroke
				(width 0.1)
				(type default)
			)
			(layer "F.Fab")
		)
		(fp_text user "+"
			(at 1.884426 -5.438902 90)
			(unlocked yes)
			(layer "F.SilkS")
			(effects
				(font
					(size 1.6002 1.1938)
					(thickness 0.1524)
				)
				(justify left)
			)
		)
		(fp_text user "+"
			(at -0.786384 -6.322314 0)
			(unlocked yes)
			(layer "F.Fab")
			(effects
				(font
					(size 1.905 1.4224)
					(thickness 0.000001)
				)
				(justify left)
			)
		)
		(pad "1" smd rect
			(at 0 -3.199892 270)
			(size 2.413 2.8194)
			(layers "F.Cu" "F.Mask" "F.Paste")
			(net "PV_VDDR_NODE1")
		)
		(pad "2" smd rect
			(at 0 3.199892 270)
			(size 2.413 2.8194)
			(layers "F.Cu" "F.Mask" "F.Paste")
			(net "GND")
		)
	)
	(footprint ""
		(layer "F.Cu")
		(at 155.987242 -136.718802 -90)
		(property "Reference" "U58"
			(at -2.787904 2.153158 0)
			(unlocked yes)
			(layer "F.SilkS")
			(effects
				(font
					(size 0.7874 0.5842)
					(thickness 0.1524)
				)
				(justify left)
			)
		)
		(property "Value" ""
			(at 0 0 270)
			(layer "F.Fab")
			(effects
				(font
					(size 1.27 1.27)
				)
			)
		)
		(duplicate_pad_numbers_are_jumpers no)
		(fp_line
			(start -1.549908 2.032)
			(end -1.549908 -2.032)
			(stroke
				(width 0.1524)
				(type default)
			)
			(layer "F.SilkS")
		)
		(fp_line
			(start 1.549908 2.032)
			(end -1.549908 2.032)
			(stroke
				(width 0.1524)
				(type default)
			)
			(layer "F.SilkS")
		)
		(fp_line
			(start -1.549908 -2.032)
			(end 1.549908 -2.032)
			(stroke
				(width 0.1524)
				(type default)
			)
			(layer "F.SilkS")
		)
		(fp_line
			(start 1.549908 -2.032)
			(end 1.549908 2.032)
			(stroke
				(width 0.1524)
				(type default)
			)
			(layer "F.SilkS")
		)
		(fp_poly
			(pts
				(xy -2.47142 1.319276) (xy -2.47142 1.827276) (xy -1.70942 1.573276)
			)
			(stroke
				(width 0)
				(type default)
			)
			(fill yes)
			(layer "F.SilkS")
		)
		(fp_poly
			(pts
				(xy -1.549908 0.849884) (xy -1.2319 0.849884) (xy -1.2319 1.9431) (xy -1.1811 1.9431) (xy 1.1811 1.9431)
				(xy 1.2319 1.9431) (xy 1.2319 0.849884) (xy 1.549908 0.849884) (xy 1.549908 -0.849884) (xy 1.2319 -0.849884)
				(xy 1.2319 -1.9431) (xy 1.1811 -1.9431) (xy -1.1811 -1.9431) (xy -1.2319 -1.9431) (xy -1.2319 -0.849884)
				(xy -1.549908 -0.849884)
			)
			(stroke
				(width 0)
				(type default)
			)
			(fill no)
			(layer "F.CrtYd")
		)
		(fp_line
			(start -1.549908 0.849884)
			(end 1.549908 0.849884)
			(stroke
				(width 0.1)
				(type default)
			)
			(layer "F.Fab")
		)
		(fp_line
			(start 1.549908 0.849884)
			(end 1.549908 -0.849884)
			(stroke
				(width 0.1)
				(type default)
			)
			(layer "F.Fab")
		)
		(fp_line
			(start -1.549908 -0.849884)
			(end -1.549908 0.849884)
			(stroke
				(width 0.1)
				(type default)
			)
			(layer "F.Fab")
		)
		(fp_line
			(start 1.549908 -0.849884)
			(end -1.549908 -0.849884)
			(stroke
				(width 0.1)
				(type default)
			)
			(layer "F.Fab")
		)
		(fp_text user "3"
			(at 2.156714 2.46761 0)
			(unlocked yes)
			(layer "F.SilkS")
			(effects
				(font
					(size 0.635 0.4064)
					(thickness 0.1524)
				)
				(justify left)
			)
		)
		(fp_text user "1"
			(at -2.05867 2.27584 0)
			(unlocked yes)
			(layer "F.SilkS")
			(effects
				(font
					(size 0.635 0.4064)
					(thickness 0.1524)
				)
				(justify left)
			)
		)
		(fp_text user "4"
			(at 0.36322 -2.219198 0)
			(unlocked yes)
			(layer "F.SilkS")
			(effects
				(font
					(size 0.635 0.4064)
					(thickness 0.1524)
				)
				(justify left)
			)
		)
		(fp_text user "5"
			(at -1.195832 -2.232914 0)
			(unlocked yes)
			(layer "F.SilkS")
			(effects
				(font
					(size 0.635 0.4064)
					(thickness 0.1524)
				)
				(justify left)
			)
		)
		(pad "1" smd rect
			(at -0.94996 1.225042 270)
			(size 0.4572 1.3208)
			(layers "F.Cu" "F.Mask" "F.Paste")
			(net "Net_1704")
		)
		(pad "2" smd rect
			(at 0 1.225042 270)
			(size 0.4572 1.3208)
			(layers "F.Cu" "F.Mask" "F.Paste")
			(net "RST_BTN_NODE1_C_L")
		)
		(pad "3" smd rect
			(at 0.94996 1.225042 270)
			(size 0.4572 1.3208)
			(layers "F.Cu" "F.Mask" "F.Paste")
			(net "GND")
		)
		(pad "4" smd rect
			(at 0.94996 -1.225042 270)
			(size 0.4572 1.3208)
			(layers "F.Cu" "F.Mask" "F.Paste")
			(net "RST_BTN_NODE1_L")
		)
		(pad "5" smd rect
			(at -0.94996 -1.225042 270)
			(size 0.4572 1.3208)
			(layers "F.Cu" "F.Mask" "F.Paste")
			(net "P3V3_STB_NODE1")
		)
	)
	(footprint ""
		(layer "F.Cu")
		(at 123.70816 -169.571416)
		(property "Reference" "R672"
			(at 30.127448 47.889922 0)
			(unlocked yes)
			(layer "F.SilkS")
			(effects
				(font
					(size 0.7874 0.5842)
					(thickness 0.1524)
				)
				(justify left)
			)
		)
		(property "Value" ""
			(at 0 0 0)
			(layer "F.Fab")
			(effects
				(font
					(size 1.27 1.27)
				)
			)
		)
		(duplicate_pad_numbers_are_jumpers no)
		(fp_line
			(start -0.7874 -0.4064)
			(end 0.7874 -0.4064)
			(stroke
				(width 0.1524)
				(type default)
			)
			(layer "F.SilkS")
		)
		(fp_line
			(start -0.7874 0.4064)
			(end -0.7874 -0.4064)
			(stroke
				(width 0.1524)
				(type default)
			)
			(layer "F.SilkS")
		)
		(fp_line
			(start 0.7874 -0.4064)
			(end 0.7874 0.4064)
			(stroke
				(width 0.1524)
				(type default)
			)
			(layer "F.SilkS")
		)
		(fp_line
			(start 0.7874 0.4064)
			(end -0.7874 0.4064)
			(stroke
				(width 0.1524)
				(type default)
			)
			(layer "F.SilkS")
		)
		(fp_poly
			(pts
				(xy -0.508 0.2794) (xy -0.508 0.2286) (xy -0.635 0.2286) (xy -0.635 -0.254) (xy -0.5334 -0.254)
				(xy -0.5334 -0.2794) (xy 0.5334 -0.2794) (xy 0.5334 -0.254) (xy 0.635 -0.254) (xy 0.635 0.254) (xy 0.5334 0.254)
				(xy 0.5334 0.2794)
			)
			(stroke
				(width 0)
				(type default)
			)
			(fill no)
			(layer "F.CrtYd")
		)
		(pad "1" smd rect
			(at 0.40005 0)
			(size 0.4572 0.508)
			(layers "F.Cu" "F.Mask" "F.Paste")
			(net "P3V3_NODE1")
		)
		(pad "2" smd rect
			(at -0.40005 0)
			(size 0.4572 0.508)
			(layers "F.Cu" "F.Mask" "F.Paste")
			(net "PU_I2C_SCL4")
		)
	)
	(footprint ""
		(layer "F.Cu")
		(at 125.735588 -182.519828 180)
		(property "Reference" "R720"
			(at -1.568704 -3.327908 0)
			(unlocked yes)
			(layer "F.SilkS")
			(effects
				(font
					(size 0.7874 0.5842)
					(thickness 0.1524)
				)
				(justify left)
			)
		)
		(property "Value" ""
			(at 0 0 180)
			(layer "F.Fab")
			(effects
				(font
					(size 1.27 1.27)
				)
			)
		)
		(duplicate_pad_numbers_are_jumpers no)
		(fp_line
			(start 0.7874 0.4064)
			(end -0.7874 0.4064)
			(stroke
				(width 0.1524)
				(type default)
			)
			(layer "F.SilkS")
		)
		(fp_line
			(start 0.7874 -0.4064)
			(end 0.7874 0.4064)
			(stroke
				(width 0.1524)
				(type default)
			)
			(layer "F.SilkS")
		)
		(fp_line
			(start -0.7874 0.4064)
			(end -0.7874 -0.4064)
			(stroke
				(width 0.1524)
				(type default)
			)
			(layer "F.SilkS")
		)
		(fp_line
			(start -0.7874 -0.4064)
			(end 0.7874 -0.4064)
			(stroke
				(width 0.1524)
				(type default)
			)
			(layer "F.SilkS")
		)
		(fp_poly
			(pts
				(xy -0.508 0.2794) (xy -0.508 0.2286) (xy -0.635 0.2286) (xy -0.635 -0.254) (xy -0.5334 -0.254)
				(xy -0.5334 -0.2794) (xy 0.5334 -0.2794) (xy 0.5334 -0.254) (xy 0.635 -0.254) (xy 0.635 0.254) (xy 0.5334 0.254)
				(xy 0.5334 0.2794)
			)
			(stroke
				(width 0)
				(type default)
			)
			(fill no)
			(layer "F.CrtYd")
		)
		(pad "1" smd rect
			(at 0.40005 0 180)
			(size 0.4572 0.508)
			(layers "F.Cu" "F.Mask" "F.Paste")
			(net "T7_NODE1_EN")
		)
		(pad "2" smd rect
			(at -0.40005 0 180)
			(size 0.4572 0.508)
			(layers "F.Cu" "F.Mask" "F.Paste")
			(net "P5V_NODE1")
		)
	)
	(footprint ""
		(layer "F.Cu")
		(at 75.766168 -183.15432)
		(property "Reference" "R1076"
			(at -4.691634 -0.262382 0)
			(unlocked yes)
			(layer "F.SilkS")
			(effects
				(font
					(size 0.7874 0.5842)
					(thickness 0.1524)
				)
				(justify left)
			)
		)
		(property "Value" ""
			(at 0 0 0)
			(layer "F.Fab")
			(effects
				(font
					(size 1.27 1.27)
				)
			)
		)
		(duplicate_pad_numbers_are_jumpers no)
		(fp_line
			(start -0.7874 -0.4064)
			(end 0.7874 -0.4064)
			(stroke
				(width 0.1524)
				(type default)
			)
			(layer "F.SilkS")
		)
		(fp_line
			(start -0.7874 0.4064)
			(end -0.7874 -0.4064)
			(stroke
				(width 0.1524)
				(type default)
			)
			(layer "F.SilkS")
		)
		(fp_line
			(start 0.7874 -0.4064)
			(end 0.7874 0.4064)
			(stroke
				(width 0.1524)
				(type default)
			)
			(layer "F.SilkS")
		)
		(fp_line
			(start 0.7874 0.4064)
			(end -0.7874 0.4064)
			(stroke
				(width 0.1524)
				(type default)
			)
			(layer "F.SilkS")
		)
		(fp_poly
			(pts
				(xy -0.508 0.2794) (xy -0.508 0.2286) (xy -0.635 0.2286) (xy -0.635 -0.254) (xy -0.5334 -0.254)
				(xy -0.5334 -0.2794) (xy 0.5334 -0.2794) (xy 0.5334 -0.254) (xy 0.635 -0.254) (xy 0.635 0.254) (xy 0.5334 0.254)
				(xy 0.5334 0.2794)
			)
			(stroke
				(width 0)
				(type default)
			)
			(fill no)
			(layer "F.CrtYd")
		)
		(pad "1" smd rect
			(at 0.40005 0)
			(size 0.4572 0.508)
			(layers "F.Cu" "F.Mask" "F.Paste")
			(net "P3V3_NODE1")
		)
		(pad "2" smd rect
			(at -0.40005 0)
			(size 0.4572 0.508)
			(layers "F.Cu" "F.Mask" "F.Paste")
			(net "JTAG_CPLD2_TDI")
		)
	)
	(footprint ""
		(layer "F.Cu")
		(at 43.41622 -145.83029 -90)
		(property "Reference" "R556"
			(at 0.886968 6.618732 90)
			(unlocked yes)
			(layer "F.SilkS")
			(effects
				(font
					(size 0.7874 0.5842)
					(thickness 0.1524)
				)
				(justify left)
			)
		)
		(property "Value" ""
			(at 0 0 270)
			(layer "F.Fab")
			(effects
				(font
					(size 1.27 1.27)
				)
			)
		)
		(duplicate_pad_numbers_are_jumpers no)
		(fp_line
			(start -0.7874 0.4064)
			(end -0.7874 -0.4064)
			(stroke
				(width 0.1524)
				(type default)
			)
			(layer "F.SilkS")
		)
		(fp_line
			(start 0.7874 0.4064)
			(end -0.7874 0.4064)
			(stroke
				(width 0.1524)
				(type default)
			)
			(layer "F.SilkS")
		)
		(fp_line
			(start -0.7874 -0.4064)
			(end 0.7874 -0.4064)
			(stroke
				(width 0.1524)
				(type default)
			)
			(layer "F.SilkS")
		)
		(fp_line
			(start 0.7874 -0.4064)
			(end 0.7874 0.4064)
			(stroke
				(width 0.1524)
				(type default)
			)
			(layer "F.SilkS")
		)
		(fp_poly
			(pts
				(xy -0.508 0.2794) (xy -0.508 0.2286) (xy -0.635 0.2286) (xy -0.635 -0.254) (xy -0.5334 -0.254)
				(xy -0.5334 -0.2794) (xy 0.5334 -0.2794) (xy 0.5334 -0.254) (xy 0.635 -0.254) (xy 0.635 0.254) (xy 0.5334 0.254)
				(xy 0.5334 0.2794)
			)
			(stroke
				(width 0)
				(type default)
			)
			(fill no)
			(layer "F.CrtYd")
		)
		(pad "1" smd rect
			(at 0.40005 0 270)
			(size 0.4572 0.508)
			(layers "F.Cu" "F.Mask" "F.Paste")
			(net "GND")
		)
		(pad "2" smd rect
			(at -0.40005 0 270)
			(size 0.4572 0.508)
			(layers "F.Cu" "F.Mask" "F.Paste")
			(net "LAN1_NC_SI_TX_EN")
		)
	)
	(footprint ""
		(layer "F.Cu")
		(at 182.234586 -143.06042)
		(property "Reference" "C448"
			(at 0.304292 1.81102 0)
			(unlocked yes)
			(layer "F.SilkS")
			(effects
				(font
					(size 0.7874 0.5842)
					(thickness 0.1524)
				)
			)
		)
		(property "Value" ""
			(at 0 0 0)
			(layer "F.Fab")
			(effects
				(font
					(size 1.27 1.27)
				)
			)
		)
		(duplicate_pad_numbers_are_jumpers no)
		(fp_line
			(start -1.2954 -0.5842)
			(end 1.2954 -0.5842)
			(stroke
				(width 0.1524)
				(type default)
			)
			(layer "F.SilkS")
		)
		(fp_line
			(start -1.2954 0.5842)
			(end -1.2954 -0.5842)
			(stroke
				(width 0.1524)
				(type default)
			)
			(layer "F.SilkS")
		)
		(fp_line
			(start 0 -0.5842)
			(end 0 0.5842)
			(stroke
				(width 0.1524)
				(type default)
			)
			(layer "F.SilkS")
		)
		(fp_line
			(start 1.2954 -0.5842)
			(end 1.2954 0.5842)
			(stroke
				(width 0.1524)
				(type default)
			)
			(layer "F.SilkS")
		)
		(fp_line
			(start 1.2954 0.5842)
			(end -1.2954 0.5842)
			(stroke
				(width 0.1524)
				(type default)
			)
			(layer "F.SilkS")
		)
		(fp_poly
			(pts
				(xy 0.8636 -0.4572) (xy 0.8636 -0.3556) (xy 1.143 -0.3556) (xy 1.143 0.3556) (xy 0.8636 0.3556)
				(xy 0.8636 0.4572) (xy -0.8636 0.4572) (xy -0.8636 0.3556) (xy -1.143 0.3556) (xy -1.143 -0.3556)
				(xy -0.8636 -0.3556) (xy -0.8636 -0.4572)
			)
			(stroke
				(width 0)
				(type default)
			)
			(fill no)
			(layer "F.CrtYd")
		)
		(fp_line
			(start -0.884936 -0.504952)
			(end 0.884936 -0.504952)
			(stroke
				(width 0.1)
				(type default)
			)
			(layer "F.Fab")
		)
		(fp_line
			(start -0.884936 0.504952)
			(end -0.884936 -0.504952)
			(stroke
				(width 0.1)
				(type default)
			)
			(layer "F.Fab")
		)
		(fp_line
			(start 0.884936 -0.504952)
			(end 0.884936 0.504952)
			(stroke
				(width 0.1)
				(type default)
			)
			(layer "F.Fab")
		)
		(fp_line
			(start 0.884936 0.504952)
			(end -0.884936 0.504952)
			(stroke
				(width 0.1)
				(type default)
			)
			(layer "F.Fab")
		)
		(pad "1" smd rect
			(at 0.7366 0 90)
			(size 0.7112 0.8128)
			(layers "F.Cu" "F.Mask" "F.Paste")
			(net "P3V3_NODE1")
		)
		(pad "2" smd rect
			(at -0.7366 0 90)
			(size 0.7112 0.8128)
			(layers "F.Cu" "F.Mask" "F.Paste")
			(net "GND")
		)
	)
	(footprint ""
		(layer "F.Cu")
		(at 125.94336 -188.126624 90)
		(property "Reference" "C623"
			(at 4.949444 -0.396748 90)
			(unlocked yes)
			(layer "F.SilkS")
			(effects
				(font
					(size 0.7874 0.5842)
					(thickness 0.1524)
				)
				(justify left)
			)
		)
		(property "Value" ""
			(at 0 0 90)
			(layer "F.Fab")
			(effects
				(font
					(size 1.27 1.27)
				)
			)
		)
		(duplicate_pad_numbers_are_jumpers no)
		(fp_line
			(start 0.7874 -0.4064)
			(end 0.7874 0.4064)
			(stroke
				(width 0.1524)
				(type default)
			)
			(layer "F.SilkS")
		)
		(fp_line
			(start -0.7874 -0.4064)
			(end 0.7874 -0.4064)
			(stroke
				(width 0.1524)
				(type default)
			)
			(layer "F.SilkS")
		)
		(fp_line
			(start 0 0.381)
			(end 0 -0.381)
			(stroke
				(width 0.1524)
				(type default)
			)
			(layer "F.SilkS")
		)
		(fp_line
			(start 0.7874 0.4064)
			(end -0.7874 0.4064)
			(stroke
				(width 0.1524)
				(type default)
			)
			(layer "F.SilkS")
		)
		(fp_line
			(start -0.7874 0.4064)
			(end -0.7874 -0.4064)
			(stroke
				(width 0.1524)
				(type default)
			)
			(layer "F.SilkS")
		)
		(fp_poly
			(pts
				(xy -0.5334 0.254) (xy -0.635 0.254) (xy -0.635 0.2286) (xy -0.635 -0.254) (xy -0.5334 -0.254) (xy -0.5334 -0.2794)
				(xy 0.5334 -0.2794) (xy 0.5334 -0.254) (xy 0.635 -0.254) (xy 0.635 0.254) (xy 0.5334 0.254) (xy 0.5334 0.2794)
				(xy -0.508 0.2794) (xy -0.5334 0.2794)
			)
			(stroke
				(width 0)
				(type default)
			)
			(fill no)
			(layer "F.CrtYd")
		)
		(pad "1" smd rect
			(at 0.40005 0 90)
			(size 0.4572 0.508)
			(layers "F.Cu" "F.Mask" "F.Paste")
			(net "T8_NODE1_EN_R")
		)
		(pad "2" smd rect
			(at -0.40005 0 90)
			(size 0.4572 0.508)
			(layers "F.Cu" "F.Mask" "F.Paste")
			(net "GND")
		)
	)
)
